(kicad_pcb
	(version 20260206)
	(generator "pcbnew")
	(generator_version "10.0")
	(general
		(thickness 1.6)
		(legacy_teardrops no)
	)
	(paper "A4")
	(title_block
		(title "03242023_DA0F0TMBIJ0_F0T_Motherboard_J_brd_V01_OCP.brd")
		(comment 1 "Grand Teton / footprint 3431 of 6105 (J28), pads 1-112 of 291")
	)
	(layers
		(0 "F.Cu" signal "TOP")
		(4 "In1.Cu" signal "GND")
		(6 "In2.Cu" signal "IN1")
		(8 "In3.Cu" signal "GND1")
		(10 "In4.Cu" signal "IN2")
		(12 "In5.Cu" signal "GND2")
		(14 "In6.Cu" signal "IN3")
		(16 "In7.Cu" signal "GND3")
		(18 "In8.Cu" signal "VCC")
		(20 "In9.Cu" signal "VCC1")
		(22 "In10.Cu" signal "GND4")
		(24 "In11.Cu" signal "IN4")
		(26 "In12.Cu" signal "GND5")
		(28 "In13.Cu" signal "IN5")
		(30 "In14.Cu" signal "GND6")
		(32 "In15.Cu" signal "IN6")
		(34 "In16.Cu" signal "GND7")
		(2 "B.Cu" signal "BOTTOM")
		(9 "F.Adhes" user "F.Adhesive")
		(11 "B.Adhes" user "B.Adhesive")
		(13 "F.Paste" user "Package Geometry/Pastemask Top")
		(15 "B.Paste" user "Package Geometry/Pastemask Bottom")
		(5 "F.SilkS" user "Ref Des/Silkscreen Top")
		(7 "B.SilkS" user "Ref Des/Silkscreen Bottom")
		(1 "F.Mask" user "Board Geometry/Soldermask Top")
		(3 "B.Mask" user "Board Geometry/Soldermask Bottom")
		(17 "Dwgs.User" user "User.Drawings")
		(19 "Cmts.User" user "User.Comments")
		(21 "Eco1.User" user "User.Eco1")
		(23 "Eco2.User" user "User.Eco2")
		(25 "Edge.Cuts" user "Board Geometry/Outline")
		(27 "Margin" user)
		(31 "F.CrtYd" user "Package Geometry/Place Bound Top")
		(29 "B.CrtYd" user "Package Geometry/Place Bound Bottom")
		(35 "F.Fab" user "Ref Des/Assembly Top")
		(33 "B.Fab" user "Ref Des/Assembly Bottom")
	)
	(footprint ""
		(layer "F.Cu")
		(at 175.95088 -258.091686)
		(property "Reference" "J28"
			(at -0.26924 -81.680812 0)
			(unlocked yes)
			(layer "F.SilkS")
			(effects
				(font
					(size 0.7874 0.5842)
					(thickness 0.1524)
				)
				(justify left)
			)
		)
		(property "Value" ""
			(at 0 0 0)
			(layer "F.Fab")
			(effects
				(font
					(size 1.27 1.27)
				)
			)
		)
		(duplicate_pad_numbers_are_jumpers no)
		(pad "1" smd rect
			(at -2.050034 -63.324994 270)
			(size 0.519938 1.4986)
			(layers "F.Cu" "F.Mask" "F.Paste")
			(net "P12V_S3_AUX_CPU1_NVDIMM")
		)
		(pad "2" smd rect
			(at -2.050034 -62.47511 270)
			(size 0.519938 1.4986)
			(layers "F.Cu" "F.Mask" "F.Paste")
			(net "TP_CHF_CPU1_DIMM2_FRU_0")
		)
		(pad "3" smd rect
			(at -2.050034 -61.624972 270)
			(size 0.519938 1.4986)
			(layers "F.Cu" "F.Mask" "F.Paste")
			(net "P3V3_AUX")
		)
		(pad "4" smd rect
			(at -2.050034 -60.775088 270)
			(size 0.519938 1.4986)
			(layers "F.Cu" "F.Mask" "F.Paste")
			(net "I3C_SPD_DDREFGH_CPU1_LVC1_SCL_3")
		)
		(pad "5" smd rect
			(at -2.050034 -59.92495 270)
			(size 0.519938 1.4986)
			(layers "F.Cu" "F.Mask" "F.Paste")
			(net "I3C_SPD_DDREFGH_CPU1_LVC1_SDA")
		)
		(pad "6" smd rect
			(at -2.050034 -59.075066 270)
			(size 0.519938 1.4986)
			(layers "F.Cu" "F.Mask" "F.Paste")
			(net "GND")
		)
		(pad "7" smd rect
			(at -2.050034 -58.224928 270)
			(size 0.519938 1.4986)
			(layers "F.Cu" "F.Mask" "F.Paste")
			(net "M_F_CPU1_SA_DQ<0>")
		)
		(pad "8" smd rect
			(at -2.050034 -57.375044 270)
			(size 0.519938 1.4986)
			(layers "F.Cu" "F.Mask" "F.Paste")
			(net "GND")
		)
		(pad "9" smd rect
			(at -2.050034 -56.524906 270)
			(size 0.519938 1.4986)
			(layers "F.Cu" "F.Mask" "F.Paste")
			(net "M_F_CPU1_SA_DQ<1>")
		)
		(pad "10" smd rect
			(at -2.050034 -55.675022 270)
			(size 0.519938 1.4986)
			(layers "F.Cu" "F.Mask" "F.Paste")
			(net "GND")
		)
		(pad "11" smd rect
			(at -2.050034 -54.824884 270)
			(size 0.519938 1.4986)
			(layers "F.Cu" "F.Mask" "F.Paste")
			(net "M_F_CPU1_SA_DQS_DP<0>")
		)
		(pad "12" smd rect
			(at -2.050034 -53.975 270)
			(size 0.519938 1.4986)
			(layers "F.Cu" "F.Mask" "F.Paste")
			(net "M_F_CPU1_SA_DQS_DN<0>")
		)
		(pad "13" smd rect
			(at -2.050034 -53.125116 270)
			(size 0.519938 1.4986)
			(layers "F.Cu" "F.Mask" "F.Paste")
			(net "GND")
		)
		(pad "14" smd rect
			(at -2.050034 -52.274978 270)
			(size 0.519938 1.4986)
			(layers "F.Cu" "F.Mask" "F.Paste")
			(net "M_F_CPU1_SA_DQ<4>")
		)
		(pad "15" smd rect
			(at -2.050034 -51.425094 270)
			(size 0.519938 1.4986)
			(layers "F.Cu" "F.Mask" "F.Paste")
			(net "GND")
		)
		(pad "16" smd rect
			(at -2.050034 -50.574956 270)
			(size 0.519938 1.4986)
			(layers "F.Cu" "F.Mask" "F.Paste")
			(net "M_F_CPU1_SA_DQ<5>")
		)
		(pad "17" smd rect
			(at -2.050034 -49.725072 270)
			(size 0.519938 1.4986)
			(layers "F.Cu" "F.Mask" "F.Paste")
			(net "GND")
		)
		(pad "18" smd rect
			(at -2.050034 -48.874934 270)
			(size 0.519938 1.4986)
			(layers "F.Cu" "F.Mask" "F.Paste")
			(net "M_F_CPU1_SA_DQ<8>")
		)
		(pad "19" smd rect
			(at -2.050034 -48.02505 270)
			(size 0.519938 1.4986)
			(layers "F.Cu" "F.Mask" "F.Paste")
			(net "GND")
		)
		(pad "20" smd rect
			(at -2.050034 -47.174912 270)
			(size 0.519938 1.4986)
			(layers "F.Cu" "F.Mask" "F.Paste")
			(net "M_F_CPU1_SA_DQ<9>")
		)
		(pad "21" smd rect
			(at -2.050034 -46.325028 270)
			(size 0.519938 1.4986)
			(layers "F.Cu" "F.Mask" "F.Paste")
			(net "GND")
		)
		(pad "22" smd rect
			(at -2.050034 -45.47489 270)
			(size 0.519938 1.4986)
			(layers "F.Cu" "F.Mask" "F.Paste")
			(net "M_F_CPU1_SA_DQS_DP<1>")
		)
		(pad "23" smd rect
			(at -2.050034 -44.625006 270)
			(size 0.519938 1.4986)
			(layers "F.Cu" "F.Mask" "F.Paste")
			(net "M_F_CPU1_SA_DQS_DN<1>")
		)
		(pad "24" smd rect
			(at -2.050034 -43.775122 270)
			(size 0.519938 1.4986)
			(layers "F.Cu" "F.Mask" "F.Paste")
			(net "GND")
		)
		(pad "25" smd rect
			(at -2.050034 -42.924984 270)
			(size 0.519938 1.4986)
			(layers "F.Cu" "F.Mask" "F.Paste")
			(net "M_F_CPU1_SA_DQ<12>")
		)
		(pad "26" smd rect
			(at -2.050034 -42.0751 270)
			(size 0.519938 1.4986)
			(layers "F.Cu" "F.Mask" "F.Paste")
			(net "GND")
		)
		(pad "27" smd rect
			(at -2.050034 -41.224962 270)
			(size 0.519938 1.4986)
			(layers "F.Cu" "F.Mask" "F.Paste")
			(net "M_F_CPU1_SA_DQ<13>")
		)
		(pad "28" smd rect
			(at -2.050034 -40.375078 270)
			(size 0.519938 1.4986)
			(layers "F.Cu" "F.Mask" "F.Paste")
			(net "GND")
		)
		(pad "29" smd rect
			(at -2.050034 -39.52494 270)
			(size 0.519938 1.4986)
			(layers "F.Cu" "F.Mask" "F.Paste")
			(net "M_F_CPU1_SA_DQ<16>")
		)
		(pad "30" smd rect
			(at -2.050034 -38.675056 270)
			(size 0.519938 1.4986)
			(layers "F.Cu" "F.Mask" "F.Paste")
			(net "GND")
		)
		(pad "31" smd rect
			(at -2.050034 -37.824918 270)
			(size 0.519938 1.4986)
			(layers "F.Cu" "F.Mask" "F.Paste")
			(net "M_F_CPU1_SA_DQ<17>")
		)
		(pad "32" smd rect
			(at -2.050034 -36.975034 270)
			(size 0.519938 1.4986)
			(layers "F.Cu" "F.Mask" "F.Paste")
			(net "GND")
		)
		(pad "33" smd rect
			(at -2.050034 -36.124896 270)
			(size 0.519938 1.4986)
			(layers "F.Cu" "F.Mask" "F.Paste")
			(net "M_F_CPU1_SA_DQS_DP<2>")
		)
		(pad "34" smd rect
			(at -2.050034 -35.275012 270)
			(size 0.519938 1.4986)
			(layers "F.Cu" "F.Mask" "F.Paste")
			(net "M_F_CPU1_SA_DQS_DN<2>")
		)
		(pad "35" smd rect
			(at -2.050034 -34.425128 270)
			(size 0.519938 1.4986)
			(layers "F.Cu" "F.Mask" "F.Paste")
			(net "GND")
		)
		(pad "36" smd rect
			(at -2.050034 -33.57499 270)
			(size 0.519938 1.4986)
			(layers "F.Cu" "F.Mask" "F.Paste")
			(net "M_F_CPU1_SA_DQ<20>")
		)
		(pad "37" smd rect
			(at -2.050034 -32.725106 270)
			(size 0.519938 1.4986)
			(layers "F.Cu" "F.Mask" "F.Paste")
			(net "GND")
		)
		(pad "38" smd rect
			(at -2.050034 -31.874968 270)
			(size 0.519938 1.4986)
			(layers "F.Cu" "F.Mask" "F.Paste")
			(net "M_F_CPU1_SA_DQ<21>")
		)
		(pad "39" smd rect
			(at -2.050034 -31.025084 270)
			(size 0.519938 1.4986)
			(layers "F.Cu" "F.Mask" "F.Paste")
			(net "GND")
		)
		(pad "40" smd rect
			(at -2.050034 -30.174946 270)
			(size 0.519938 1.4986)
			(layers "F.Cu" "F.Mask" "F.Paste")
			(net "M_F_CPU1_SA_DQ<24>")
		)
		(pad "41" smd rect
			(at -2.050034 -29.325062 270)
			(size 0.519938 1.4986)
			(layers "F.Cu" "F.Mask" "F.Paste")
			(net "GND")
		)
		(pad "42" smd rect
			(at -2.050034 -28.474924 270)
			(size 0.519938 1.4986)
			(layers "F.Cu" "F.Mask" "F.Paste")
			(net "M_F_CPU1_SA_DQ<25>")
		)
		(pad "43" smd rect
			(at -2.050034 -27.62504 270)
			(size 0.519938 1.4986)
			(layers "F.Cu" "F.Mask" "F.Paste")
			(net "GND")
		)
		(pad "44" smd rect
			(at -2.050034 -26.774902 270)
			(size 0.519938 1.4986)
			(layers "F.Cu" "F.Mask" "F.Paste")
			(net "M_F_CPU1_SA_DQS_DP<3>")
		)
		(pad "45" smd rect
			(at -2.050034 -25.925018 270)
			(size 0.519938 1.4986)
			(layers "F.Cu" "F.Mask" "F.Paste")
			(net "M_F_CPU1_SA_DQS_DN<3>")
		)
		(pad "46" smd rect
			(at -2.050034 -25.07488 270)
			(size 0.519938 1.4986)
			(layers "F.Cu" "F.Mask" "F.Paste")
			(net "GND")
		)
		(pad "47" smd rect
			(at -2.050034 -24.224996 270)
			(size 0.519938 1.4986)
			(layers "F.Cu" "F.Mask" "F.Paste")
			(net "M_F_CPU1_SA_DQ<28>")
		)
		(pad "48" smd rect
			(at -2.050034 -23.375112 270)
			(size 0.519938 1.4986)
			(layers "F.Cu" "F.Mask" "F.Paste")
			(net "GND")
		)
		(pad "49" smd rect
			(at -2.050034 -22.524974 270)
			(size 0.519938 1.4986)
			(layers "F.Cu" "F.Mask" "F.Paste")
			(net "M_F_CPU1_SA_DQ<29>")
		)
		(pad "50" smd rect
			(at -2.050034 -21.67509 270)
			(size 0.519938 1.4986)
			(layers "F.Cu" "F.Mask" "F.Paste")
			(net "GND")
		)
		(pad "51" smd rect
			(at -2.050034 -20.824952 270)
			(size 0.519938 1.4986)
			(layers "F.Cu" "F.Mask" "F.Paste")
			(net "M_F_CPU1_SA_CB<0>")
		)
		(pad "52" smd rect
			(at -2.050034 -19.975068 270)
			(size 0.519938 1.4986)
			(layers "F.Cu" "F.Mask" "F.Paste")
			(net "GND")
		)
		(pad "53" smd rect
			(at -2.050034 -19.12493 270)
			(size 0.519938 1.4986)
			(layers "F.Cu" "F.Mask" "F.Paste")
			(net "M_F_CPU1_SA_CB<1>")
		)
		(pad "54" smd rect
			(at -2.050034 -18.275046 270)
			(size 0.519938 1.4986)
			(layers "F.Cu" "F.Mask" "F.Paste")
			(net "GND")
		)
		(pad "55" smd rect
			(at -2.050034 -17.424908 270)
			(size 0.519938 1.4986)
			(layers "F.Cu" "F.Mask" "F.Paste")
			(net "M_F_CPU1_SA_DQS_DP<4>")
		)
		(pad "56" smd rect
			(at -2.050034 -16.575024 270)
			(size 0.519938 1.4986)
			(layers "F.Cu" "F.Mask" "F.Paste")
			(net "M_F_CPU1_SA_DQS_DN<4>")
		)
		(pad "57" smd rect
			(at -2.050034 -15.724886 270)
			(size 0.519938 1.4986)
			(layers "F.Cu" "F.Mask" "F.Paste")
			(net "GND")
		)
		(pad "58" smd rect
			(at -2.050034 -14.875002 270)
			(size 0.519938 1.4986)
			(layers "F.Cu" "F.Mask" "F.Paste")
			(net "M_F_CPU1_SA_CB<4>")
		)
		(pad "59" smd rect
			(at -2.050034 -14.025118 270)
			(size 0.519938 1.4986)
			(layers "F.Cu" "F.Mask" "F.Paste")
			(net "GND")
		)
		(pad "60" smd rect
			(at -2.050034 -13.17498 270)
			(size 0.519938 1.4986)
			(layers "F.Cu" "F.Mask" "F.Paste")
			(net "M_F_CPU1_SA_CB<5>")
		)
		(pad "61" smd rect
			(at -2.050034 -12.325096 270)
			(size 0.519938 1.4986)
			(layers "F.Cu" "F.Mask" "F.Paste")
			(net "GND")
		)
		(pad "62" smd rect
			(at -2.050034 -11.474958 270)
			(size 0.519938 1.4986)
			(layers "F.Cu" "F.Mask" "F.Paste")
			(net "M_F_CPU1_ALERT_N")
		)
		(pad "63" smd rect
			(at -2.050034 -10.625074 270)
			(size 0.519938 1.4986)
			(layers "F.Cu" "F.Mask" "F.Paste")
			(net "GND")
		)
		(pad "64" smd rect
			(at -2.050034 -9.774936 270)
			(size 0.519938 1.4986)
			(layers "F.Cu" "F.Mask" "F.Paste")
			(net "M_F_CPU1_SA_CS_N<2>")
		)
		(pad "65" smd rect
			(at -2.050034 -8.925052 270)
			(size 0.519938 1.4986)
			(layers "F.Cu" "F.Mask" "F.Paste")
			(net "GND")
		)
		(pad "66" smd rect
			(at -2.050034 -8.074914 270)
			(size 0.519938 1.4986)
			(layers "F.Cu" "F.Mask" "F.Paste")
			(net "M_F_CPU1_SA_CA<0>")
		)
		(pad "67" smd rect
			(at -2.050034 -7.22503 270)
			(size 0.519938 1.4986)
			(layers "F.Cu" "F.Mask" "F.Paste")
			(net "GND")
		)
		(pad "68" smd rect
			(at -2.050034 -6.374892 270)
			(size 0.519938 1.4986)
			(layers "F.Cu" "F.Mask" "F.Paste")
			(net "M_F_CPU1_SA_CA<2>")
		)
		(pad "69" smd rect
			(at -2.050034 -5.525008 270)
			(size 0.519938 1.4986)
			(layers "F.Cu" "F.Mask" "F.Paste")
			(net "GND")
		)
		(pad "70" smd rect
			(at -2.050034 -4.675124 270)
			(size 0.519938 1.4986)
			(layers "F.Cu" "F.Mask" "F.Paste")
			(net "M_F_CPU1_SA_CA<4>")
		)
		(pad "71" smd rect
			(at -2.050034 -3.824986 270)
			(size 0.519938 1.4986)
			(layers "F.Cu" "F.Mask" "F.Paste")
			(net "GND")
		)
		(pad "72" smd rect
			(at -2.050034 -2.975102 270)
			(size 0.519938 1.4986)
			(layers "F.Cu" "F.Mask" "F.Paste")
			(net "M_F_CPU1_SA_CA<6>")
		)
		(pad "73" smd rect
			(at -2.050034 -2.124964 270)
			(size 0.519938 1.4986)
			(layers "F.Cu" "F.Mask" "F.Paste")
			(net "GND")
		)
		(pad "74" smd rect
			(at -2.050034 -1.27508 270)
			(size 0.519938 1.4986)
			(layers "F.Cu" "F.Mask" "F.Paste")
			(net "M_F_CPU1_SA_PAR")
		)
		(pad "75" smd rect
			(at -2.050034 -0.424942 270)
			(size 0.519938 1.4986)
			(layers "F.Cu" "F.Mask" "F.Paste")
			(net "GND")
		)
		(pad "76" smd rect
			(at -2.050034 5.525008 270)
			(size 0.519938 1.4986)
			(layers "F.Cu" "F.Mask" "F.Paste")
			(net "M_F_CPU1_SB_CA<0>")
		)
		(pad "77" smd rect
			(at -2.050034 6.374892 270)
			(size 0.519938 1.4986)
			(layers "F.Cu" "F.Mask" "F.Paste")
			(net "GND")
		)
		(pad "78" smd rect
			(at -2.050034 7.22503 270)
			(size 0.519938 1.4986)
			(layers "F.Cu" "F.Mask" "F.Paste")
			(net "M_F_CPU1_SB_CA<2>")
		)
		(pad "79" smd rect
			(at -2.050034 8.074914 270)
			(size 0.519938 1.4986)
			(layers "F.Cu" "F.Mask" "F.Paste")
			(net "GND")
		)
		(pad "80" smd rect
			(at -2.050034 8.925052 270)
			(size 0.519938 1.4986)
			(layers "F.Cu" "F.Mask" "F.Paste")
			(net "M_F_CPU1_SB_CA<4>")
		)
		(pad "81" smd rect
			(at -2.050034 9.774936 270)
			(size 0.519938 1.4986)
			(layers "F.Cu" "F.Mask" "F.Paste")
			(net "GND")
		)
		(pad "82" smd rect
			(at -2.050034 10.625074 270)
			(size 0.519938 1.4986)
			(layers "F.Cu" "F.Mask" "F.Paste")
			(net "M_F_CPU1_SB_CA<6>")
		)
		(pad "83" smd rect
			(at -2.050034 11.474958 270)
			(size 0.519938 1.4986)
			(layers "F.Cu" "F.Mask" "F.Paste")
			(net "GND")
		)
		(pad "84" smd rect
			(at -2.050034 12.325096 270)
			(size 0.519938 1.4986)
			(layers "F.Cu" "F.Mask" "F.Paste")
			(net "M_F_CPU1_SB_CS_N<2>")
		)
		(pad "85" smd rect
			(at -2.050034 13.17498 270)
			(size 0.519938 1.4986)
			(layers "F.Cu" "F.Mask" "F.Paste")
			(net "GND")
		)
		(pad "86" smd rect
			(at -2.050034 14.025118 270)
			(size 0.519938 1.4986)
			(layers "F.Cu" "F.Mask" "F.Paste")
			(net "M_F_CPU1_SA_RSP<1>")
		)
		(pad "87" smd rect
			(at -2.050034 14.875002 270)
			(size 0.519938 1.4986)
			(layers "F.Cu" "F.Mask" "F.Paste")
			(net "M_F_CPU1_SB_RSP<1>")
		)
		(pad "88" smd rect
			(at -2.050034 15.724886 270)
			(size 0.519938 1.4986)
			(layers "F.Cu" "F.Mask" "F.Paste")
			(net "GND")
		)
		(pad "89" smd rect
			(at -2.050034 16.575024 270)
			(size 0.519938 1.4986)
			(layers "F.Cu" "F.Mask" "F.Paste")
			(net "M_F_CPU1_SB_CB<4>")
		)
		(pad "90" smd rect
			(at -2.050034 17.424908 270)
			(size 0.519938 1.4986)
			(layers "F.Cu" "F.Mask" "F.Paste")
			(net "GND")
		)
		(pad "91" smd rect
			(at -2.050034 18.275046 270)
			(size 0.519938 1.4986)
			(layers "F.Cu" "F.Mask" "F.Paste")
			(net "M_F_CPU1_SB_CB<5>")
		)
		(pad "92" smd rect
			(at -2.050034 19.12493 270)
			(size 0.519938 1.4986)
			(layers "F.Cu" "F.Mask" "F.Paste")
			(net "GND")
		)
		(pad "93" smd rect
			(at -2.050034 19.975068 270)
			(size 0.519938 1.4986)
			(layers "F.Cu" "F.Mask" "F.Paste")
			(net "M_F_CPU1_SB_DQS_DP<9>")
		)
		(pad "94" smd rect
			(at -2.050034 20.824952 270)
			(size 0.519938 1.4986)
			(layers "F.Cu" "F.Mask" "F.Paste")
			(net "M_F_CPU1_SB_DQS_DN<9>")
		)
		(pad "95" smd rect
			(at -2.050034 21.67509 270)
			(size 0.519938 1.4986)
			(layers "F.Cu" "F.Mask" "F.Paste")
			(net "GND")
		)
		(pad "96" smd rect
			(at -2.050034 22.524974 270)
			(size 0.519938 1.4986)
			(layers "F.Cu" "F.Mask" "F.Paste")
			(net "M_F_CPU1_SB_CB<0>")
		)
		(pad "97" smd rect
			(at -2.050034 23.375112 270)
			(size 0.519938 1.4986)
			(layers "F.Cu" "F.Mask" "F.Paste")
			(net "GND")
		)
		(pad "98" smd rect
			(at -2.050034 24.224996 270)
			(size 0.519938 1.4986)
			(layers "F.Cu" "F.Mask" "F.Paste")
			(net "M_F_CPU1_SB_CB<1>")
		)
		(pad "99" smd rect
			(at -2.050034 25.07488 270)
			(size 0.519938 1.4986)
			(layers "F.Cu" "F.Mask" "F.Paste")
			(net "GND")
		)
		(pad "100" smd rect
			(at -2.050034 25.925018 270)
			(size 0.519938 1.4986)
			(layers "F.Cu" "F.Mask" "F.Paste")
			(net "M_F_CPU1_SB_DQ<0>")
		)
		(pad "101" smd rect
			(at -2.050034 26.774902 270)
			(size 0.519938 1.4986)
			(layers "F.Cu" "F.Mask" "F.Paste")
			(net "GND")
		)
		(pad "102" smd rect
			(at -2.050034 27.62504 270)
			(size 0.519938 1.4986)
			(layers "F.Cu" "F.Mask" "F.Paste")
			(net "M_F_CPU1_SB_DQ<1>")
		)
		(pad "103" smd rect
			(at -2.050034 28.474924 270)
			(size 0.519938 1.4986)
			(layers "F.Cu" "F.Mask" "F.Paste")
			(net "GND")
		)
		(pad "104" smd rect
			(at -2.050034 29.325062 270)
			(size 0.519938 1.4986)
			(layers "F.Cu" "F.Mask" "F.Paste")
			(net "M_F_CPU1_SB_DQS_DP<0>")
		)
		(pad "105" smd rect
			(at -2.050034 30.174946 270)
			(size 0.519938 1.4986)
			(layers "F.Cu" "F.Mask" "F.Paste")
			(net "M_F_CPU1_SB_DQS_DN<0>")
		)
		(pad "106" smd rect
			(at -2.050034 31.025084 270)
			(size 0.519938 1.4986)
			(layers "F.Cu" "F.Mask" "F.Paste")
			(net "GND")
		)
		(pad "107" smd rect
			(at -2.050034 31.874968 270)
			(size 0.519938 1.4986)
			(layers "F.Cu" "F.Mask" "F.Paste")
			(net "M_F_CPU1_SB_DQ<4>")
		)
		(pad "108" smd rect
			(at -2.050034 32.725106 270)
			(size 0.519938 1.4986)
			(layers "F.Cu" "F.Mask" "F.Paste")
			(net "GND")
		)
		(pad "109" smd rect
			(at -2.050034 33.57499 270)
			(size 0.519938 1.4986)
			(layers "F.Cu" "F.Mask" "F.Paste")
			(net "M_F_CPU1_SB_DQ<5>")
		)
		(pad "110" smd rect
			(at -2.050034 34.425128 270)
			(size 0.519938 1.4986)
			(layers "F.Cu" "F.Mask" "F.Paste")
			(net "GND")
		)
		(pad "111" smd rect
			(at -2.050034 35.275012 270)
			(size 0.519938 1.4986)
			(layers "F.Cu" "F.Mask" "F.Paste")
			(net "M_F_CPU1_SB_DQ<8>")
		)
		(pad "112" smd rect
			(at -2.050034 36.124896 270)
			(size 0.519938 1.4986)
			(layers "F.Cu" "F.Mask" "F.Paste")
			(net "GND")
		)
	)
)
